# BASEBOARD_FAB2 (Tioga Pass) — schematic netlist excerpt (pin names and nets, part order shuffled) for the footprints in the layout excerpt that follows; sources: Cadence DE-HDL packaged netlist, KiCad conversion of Wiwynn_Tioga_Pass_MB.brd

R6F3  RES  10.0K 1% CHIP  pkg 0402  page 89 : A = PVPP_ABC ; B = IRQ_DIMM_SAVE_N
CT16  CAP_A  0.1UF 16V 10% X7R  pkg 0402V  page 208 : A = VR_PVCCIN_CPU1_AIREF3 ; B = GND
C1D27  CAP_A  0.1UF 16V 10% X7R  pkg 0402V  page 199 : A = A_HSC_OV ; B = AGND_HSC

(kicad_pcb
	(version 20260206)
	(generator "pcbnew")
	(generator_version "10.0")
	(general
		(thickness 1.6)
		(legacy_teardrops no)
	)
	(paper "A4")
	(title_block
		(title "Wiwynn_Tioga_Pass_MB.brd")
		(comment 1 "Tioga Pass / footprints 1723-1725 of 4770")
	)
	(layers
		(0 "F.Cu" signal "TOP")
		(4 "In1.Cu" signal "L2GND")
		(6 "In2.Cu" signal "L3")
		(8 "In3.Cu" signal "L4GND")
		(10 "In4.Cu" signal "L5")
		(12 "In5.Cu" signal "L6GND")
		(14 "In6.Cu" signal "L7VCC")
		(16 "In7.Cu" signal "L8VCC")
		(18 "In8.Cu" signal "L9GND")
		(20 "In9.Cu" signal "L10")
		(22 "In10.Cu" signal "L11GND")
		(24 "In11.Cu" signal "L12")
		(26 "In12.Cu" signal "L13GND")
		(2 "B.Cu" signal "BOTTOM")
		(9 "F.Adhes" user "F.Adhesive")
		(11 "B.Adhes" user "B.Adhesive")
		(13 "F.Paste" user "Package Geometry/Pastemask Top")
		(15 "B.Paste" user "Package Geometry/Pastemask Bottom")
		(5 "F.SilkS" user "Ref Des/Silkscreen Top")
		(7 "B.SilkS" user "Ref Des/Silkscreen Bottom")
		(1 "F.Mask" user "Board Geometry/Soldermask Top")
		(3 "B.Mask" user "Board Geometry/Soldermask Bottom")
		(17 "Dwgs.User" user "User.Drawings")
		(19 "Cmts.User" user "User.Comments")
		(21 "Eco1.User" user "User.Eco1")
		(23 "Eco2.User" user "User.Eco2")
		(25 "Edge.Cuts" user "Board Geometry/Outline")
		(27 "Margin" user)
		(31 "F.CrtYd" user "Package Geometry/Place Bound Top")
		(29 "B.CrtYd" user "Package Geometry/Place Bound Bottom")
		(35 "F.Fab" user "Ref Des/Assembly Top")
		(33 "B.Fab" user "Ref Des/Assembly Bottom")
	)
	(footprint ""
		(layer "F.Cu")
		(at 324.612 -35.052 -90)
		(property "Reference" "R6F3"
			(at 0 0 270)
			(layer "F.SilkS")
			(hide yes)
			(effects
				(font
					(size 1.27 1.27)
				)
			)
		)
		(property "Value" ""
			(at 0 0 270)
			(layer "F.Fab")
			(effects
				(font
					(size 1.27 1.27)
				)
			)
		)
		(duplicate_pad_numbers_are_jumpers no)
		(fp_poly
			(pts
				(xy -0.2794 -0.1016) (xy 0.2794 -0.1016) (xy 0.2794 0.9906) (xy -0.2794 0.9906)
			)
			(stroke
				(width 0)
				(type default)
			)
			(fill no)
			(layer "F.CrtYd")
		)
		(fp_line
			(start -0.2794 0.9906)
			(end 0.2794 0.9906)
			(stroke
				(width 0.1)
				(type default)
			)
			(layer "F.Fab")
		)
		(fp_line
			(start 0.2794 0.9906)
			(end 0.2794 -0.1016)
			(stroke
				(width 0.1)
				(type default)
			)
			(layer "F.Fab")
		)
		(fp_line
			(start -0.2794 -0.1016)
			(end -0.2794 0.9906)
			(stroke
				(width 0.1)
				(type default)
			)
			(layer "F.Fab")
		)
		(fp_line
			(start 0.2794 -0.1016)
			(end -0.2794 -0.1016)
			(stroke
				(width 0.1)
				(type default)
			)
			(layer "F.Fab")
		)
		(pad "1" smd rect
			(at 0 0 270)
			(size 0.508 0.508)
			(layers "F.Cu" "F.Mask" "F.Paste")
			(net "PVPP_ABC")
		)
		(pad "2" smd rect
			(at 0 0.889 270)
			(size 0.508 0.508)
			(layers "F.Cu" "F.Mask" "F.Paste")
			(net "IRQ_DIMM_SAVE_N")
		)
		(zone
			(layer "F.Cu")
			(hatch none 0.5)
			(connect_pads
				(clearance 0)
			)
			(min_thickness 0.25)
			(keepout
				(tracks not_allowed)
				(vias allowed)
				(pads allowed)
				(copperpour not_allowed)
				(footprints allowed)
			)
			(placement
				(enabled no)
				(sheetname "")
			)
			(fill
				(thermal_gap 0.5)
				(thermal_bridge_width 0.5)
				(island_removal_mode 0)
			)
			(polygon
				(pts
					(xy 323.977 -35.306) (xy 323.977 -34.798) (xy 324.358 -34.798) (xy 324.358 -35.306)
				)
			)
		)
		(zone
			(layer "F.Cu")
			(hatch none 0.5)
			(connect_pads
				(clearance 0)
			)
			(min_thickness 0.25)
			(keepout
				(tracks allowed)
				(vias not_allowed)
				(pads allowed)
				(copperpour not_allowed)
				(footprints allowed)
			)
			(placement
				(enabled no)
				(sheetname "")
			)
			(fill
				(thermal_gap 0.5)
				(thermal_bridge_width 0.5)
				(island_removal_mode 0)
			)
			(polygon
				(pts
					(xy 324.358 -35.306) (xy 324.358 -34.798) (xy 323.977 -34.798) (xy 323.977 -35.306)
				)
			)
		)
	)
	(footprint ""
		(layer "F.Cu")
		(at 21.336 -70.866)
		(property "Reference" "C1D27"
			(at 0 0 0)
			(layer "F.SilkS")
			(hide yes)
			(effects
				(font
					(size 1.27 1.27)
				)
			)
		)
		(property "Value" ""
			(at 0 0 0)
			(layer "F.Fab")
			(effects
				(font
					(size 1.27 1.27)
				)
			)
		)
		(duplicate_pad_numbers_are_jumpers no)
		(fp_rect
			(start 0.3048 0.9906)
			(end -0.3048 -0.1016)
			(stroke
				(width 0)
				(type default)
			)
			(fill no)
			(layer "F.CrtYd")
		)
		(fp_line
			(start -0.3048 -0.1016)
			(end -0.3048 0.9906)
			(stroke
				(width 0.1)
				(type default)
			)
			(layer "F.Fab")
		)
		(fp_line
			(start -0.3048 0.9906)
			(end 0.3048 0.9906)
			(stroke
				(width 0.1)
				(type default)
			)
			(layer "F.Fab")
		)
		(fp_line
			(start 0.3048 -0.1016)
			(end -0.3048 -0.1016)
			(stroke
				(width 0.1)
				(type default)
			)
			(layer "F.Fab")
		)
		(fp_line
			(start 0.3048 0.9906)
			(end 0.3048 -0.1016)
			(stroke
				(width 0.1)
				(type default)
			)
			(layer "F.Fab")
		)
		(pad "1" smd rect
			(at 0 0)
			(size 0.508 0.508)
			(layers "F.Cu" "F.Mask" "F.Paste")
			(net "A_HSC_OV")
		)
		(pad "2" smd rect
			(at 0 0.889)
			(size 0.508 0.508)
			(layers "F.Cu" "F.Mask" "F.Paste")
			(net "AGND_HSC")
		)
		(zone
			(layer "F.Cu")
			(hatch none 0.5)
			(connect_pads
				(clearance 0)
			)
			(min_thickness 0.25)
			(keepout
				(tracks not_allowed)
				(vias allowed)
				(pads allowed)
				(copperpour not_allowed)
				(footprints allowed)
			)
			(placement
				(enabled no)
				(sheetname "")
			)
			(fill
				(thermal_gap 0.5)
				(thermal_bridge_width 0.5)
				(island_removal_mode 0)
			)
			(polygon
				(pts
					(xy 21.59 -70.231) (xy 21.59 -70.612) (xy 21.082 -70.612) (xy 21.082 -70.231)
				)
			)
		)
		(zone
			(layer "F.Cu")
			(hatch none 0.5)
			(connect_pads
				(clearance 0)
			)
			(min_thickness 0.25)
			(keepout
				(tracks allowed)
				(vias not_allowed)
				(pads allowed)
				(copperpour not_allowed)
				(footprints allowed)
			)
			(placement
				(enabled no)
				(sheetname "")
			)
			(fill
				(thermal_gap 0.5)
				(thermal_bridge_width 0.5)
				(island_removal_mode 0)
			)
			(polygon
				(pts
					(xy 21.59 -70.231) (xy 21.59 -70.612) (xy 21.082 -70.612) (xy 21.082 -70.231)
				)
			)
		)
	)
	(footprint ""
		(layer "F.Cu")
		(at 30.3276 -69.8754)
		(property "Reference" "CT16"
			(at -0.88773 0.6858 90)
			(unlocked yes)
			(layer "F.SilkS")
			(effects
				(font
					(size 0.7874 0.5842)
					(thickness 0.1524)
				)
				(justify left)
			)
		)
		(property "Value" ""
			(at 0 0 0)
			(layer "F.Fab")
			(effects
				(font
					(size 1.27 1.27)
				)
			)
		)
		(duplicate_pad_numbers_are_jumpers no)
		(fp_poly
			(pts
				(xy 0.3048 -0.1016) (xy 0.3048 0.9906) (xy -0.3048 0.9906) (xy -0.3048 -0.1016)
			)
			(stroke
				(width 0)
				(type default)
			)
			(fill no)
			(layer "F.CrtYd")
		)
		(fp_line
			(start -0.3048 -0.1016)
			(end -0.3048 0.9906)
			(stroke
				(width 0.1)
				(type default)
			)
			(layer "F.Fab")
		)
		(fp_line
			(start -0.3048 0.9906)
			(end 0.3048 0.9906)
			(stroke
				(width 0.1)
				(type default)
			)
			(layer "F.Fab")
		)
		(fp_line
			(start 0.3048 -0.1016)
			(end -0.3048 -0.1016)
			(stroke
				(width 0.1)
				(type default)
			)
			(layer "F.Fab")
		)
		(fp_line
			(start 0.3048 0.9906)
			(end 0.3048 -0.1016)
			(stroke
				(width 0.1)
				(type default)
			)
			(layer "F.Fab")
		)
		(pad "1" smd rect
			(at 0 0)
			(size 0.508 0.508)
			(layers "F.Cu" "F.Mask" "F.Paste")
			(net "VR_PVCCIN_CPU1_AIREF3")
		)
		(pad "2" smd rect
			(at 0 0.889)
			(size 0.508 0.508)
			(layers "F.Cu" "F.Mask" "F.Paste")
			(net "GND")
		)
		(zone
			(layer "F.Cu")
			(hatch none 0.5)
			(connect_pads
				(clearance 0)
			)
			(min_thickness 0.25)
			(keepout
				(tracks allowed)
				(vias not_allowed)
				(pads allowed)
				(copperpour not_allowed)
				(footprints allowed)
			)
			(placement
				(enabled no)
				(sheetname "")
			)
			(fill
				(thermal_gap 0.5)
				(thermal_bridge_width 0.5)
				(island_removal_mode 0)
			)
			(polygon
				(pts
					(xy 30.0736 -69.6214) (xy 30.5816 -69.6214) (xy 30.5816 -69.2404) (xy 30.0736 -69.2404)
				)
			)
		)
		(zone
			(layer "F.Cu")
			(hatch none 0.5)
			(connect_pads
				(clearance 0)
			)
			(min_thickness 0.25)
			(keepout
				(tracks not_allowed)
				(vias allowed)
				(pads allowed)
				(copperpour not_allowed)
				(footprints allowed)
			)
			(placement
				(enabled no)
				(sheetname "")
			)
			(fill
				(thermal_gap 0.5)
				(thermal_bridge_width 0.5)
				(island_removal_mode 0)
			)
			(polygon
				(pts
					(xy 30.0736 -69.2404) (xy 30.5816 -69.2404) (xy 30.5816 -69.6214) (xy 30.0736 -69.6214)
				)
			)
		)
	)
)
